(kicad_pcb
	(version 20260206)
	(generator "pcbnew")
	(generator_version "10.0")
	(general
		(thickness 1.21888)
		(legacy_teardrops no)
	)
	(paper "A4")
	(title_block
		(title "timecard-beta-v1 — TimeCard-DC-V1.PcbDoc")
		(comment 1 "Time Appliance Project (Time Card) / footprints 1-16 of 120")
	)
	(layers
		(0 "F.Cu" signal "TOP")
		(4 "In1.Cu" signal "SGND")
		(6 "In2.Cu" signal "IN1")
		(8 "In3.Cu" signal "IN2")
		(10 "In4.Cu" signal "SGND1")
		(2 "B.Cu" signal "BOTTOM")
		(9 "F.Adhes" user "F.Adhesive")
		(11 "B.Adhes" user "B.Adhesive")
		(13 "F.Paste" user "Top Paste")
		(15 "B.Paste" user "Bottom Paste")
		(5 "F.SilkS" user "Top Overlay")
		(7 "B.SilkS" user "Bottom Overlay")
		(1 "F.Mask" user "Top Solder")
		(3 "B.Mask" user "Bottom Solder")
		(17 "Dwgs.User" user "User.Drawings")
		(19 "Cmts.User" user "User.Comments")
		(21 "Eco1.User" user "User.Eco1")
		(23 "Eco2.User" user "User.Eco2")
		(25 "Edge.Cuts" user)
		(27 "Margin" user)
		(31 "F.CrtYd" user "Top Courtyard")
		(29 "B.CrtYd" user "Bottom Courtyard")
		(35 "F.Fab" user "Top Component Center")
		(33 "B.Fab" user "Bottom Component Center")
	)
	(footprint "Capacitors:CAPC2012X14N"
		(layer "F.Cu")
		(at 149.662595 142.1366 180)
		(property "Reference" "C62"
			(at 4.849 -0.335345 0)
			(unlocked yes)
			(layer "F.SilkS")
			(effects
				(font
					(size 0.762 0.762)
					(thickness 0.2286)
				)
				(justify left bottom)
			)
		)
		(property "Value" "CAP_0805_10UF_25V"
			(at 1.5875 -3.52679 0)
			(unlocked yes)
			(layer "F.SilkS")
			(hide yes)
			(effects
				(font
					(size 1.524 1.524)
					(thickness 0.254)
				)
				(justify left bottom)
			)
		)
		(sheetname "MAC")
		(sheetfile "MAC.kicad_sch")
		(duplicate_pad_numbers_are_jumpers no)
		(fp_line
			(start 0.762 0.9652)
			(end -0.762 0.9652)
			(stroke
				(width 0.1524)
				(type solid)
			)
			(layer "F.SilkS")
		)
		(fp_line
			(start 0.762 -0.9652)
			(end -0.762 -0.9652)
			(stroke
				(width 0.1524)
				(type solid)
			)
			(layer "F.SilkS")
		)
		(pad "1" smd rect
			(at -0.9 0 270)
			(size 1.45 1.15)
			(layers "F.Cu" "F.Mask" "F.Paste")
			(net "+5.0V")
		)
		(pad "2" smd rect
			(at 0.9 0 270)
			(size 1.45 1.15)
			(layers "F.Cu" "F.Mask" "F.Paste")
			(net "GND")
		)
	)
	(footprint "Resistors:RESC1608X50N"
		(layer "F.Cu")
		(at 94.548595 122.0786 180)
		(property "Reference" "R22"
			(at 1.06 0.906655 0)
			(unlocked yes)
			(layer "F.SilkS")
			(effects
				(font
					(size 0.762 0.762)
					(thickness 0.2286)
				)
				(justify left bottom)
			)
		)
		(property "Value" "ERJ-3EKF4701V"
			(at 0.4445 -3.72999 0)
			(unlocked yes)
			(layer "F.SilkS")
			(hide yes)
			(effects
				(font
					(size 1.524 1.524)
					(thickness 0.254)
				)
				(justify left bottom)
			)
		)
		(sheetname "PCIe_JTAG")
		(sheetfile "PCIe_JTAG.kicad_sch")
		(duplicate_pad_numbers_are_jumpers no)
		(fp_line
			(start 0 -0.5)
			(end 0 0.5)
			(stroke
				(width 0.1524)
				(type solid)
			)
			(layer "F.SilkS")
		)
		(pad "1" smd rect
			(at -0.69 0 270)
			(size 1 0.72)
			(layers "F.Cu" "F.Mask" "F.Paste")
			(net "PCIE_PERST")
		)
		(pad "2" smd rect
			(at 0.69 0 270)
			(size 1 0.72)
			(layers "F.Cu" "F.Mask" "F.Paste")
			(net "+3.3V")
		)
	)
	(footprint "Resistors:RESC1608X50N"
		(layer "F.Cu")
		(at 230.288595 114.3786)
		(property "Reference" "R6"
			(at -3.398 0.321345 0)
			(unlocked yes)
			(layer "F.SilkS")
			(effects
				(font
					(size 0.762 0.762)
					(thickness 0.2286)
				)
				(justify left bottom)
			)
		)
		(property "Value" "ERJ-3EKF1002V"
			(at -4.4323 3.04419 0)
			(unlocked yes)
			(layer "F.SilkS")
			(hide yes)
			(effects
				(font
					(size 1.524 1.524)
					(thickness 0.254)
				)
				(justify left bottom)
			)
		)
		(sheetname "POWER")
		(sheetfile "POWER.kicad_sch")
		(duplicate_pad_numbers_are_jumpers no)
		(fp_line
			(start 0 0.5)
			(end 0 -0.5)
			(stroke
				(width 0.1524)
				(type solid)
			)
			(layer "F.SilkS")
		)
		(pad "1" smd rect
			(at -0.69 0 90)
			(size 1 0.72)
			(layers "F.Cu" "F.Mask" "F.Paste")
			(net "GND")
		)
		(pad "2" smd rect
			(at 0.69 0 90)
			(size 1 0.72)
			(layers "F.Cu" "F.Mask" "F.Paste")
			(net "NetR4_2")
		)
	)
	(footprint "Vault:CAPC1608X87X45ML20T05"
		(layer "F.Cu")
		(at 131.238595 75.3286 90)
		(property "Reference" "C59"
			(at -4.25 1.343345 90)
			(unlocked yes)
			(layer "F.SilkS")
			(effects
				(font
					(size 0.762 0.762)
					(thickness 0.2286)
				)
				(justify left bottom)
			)
		)
		(property "Value" "0.1uF"
			(at -3.47599 -0.2921 0)
			(unlocked yes)
			(layer "F.SilkS")
			(hide yes)
			(effects
				(font
					(size 1.524 1.524)
					(thickness 0.254)
				)
				(justify left bottom)
			)
		)
		(sheetname "GPS_IMU_SENSORS")
		(sheetfile "GPS_IMU_SENSORS.kicad_sch")
		(duplicate_pad_numbers_are_jumpers no)
		(pad "1" smd rect
			(at -0.7 0 180)
			(size 1.1 1.05)
			(layers "F.Cu" "F.Mask" "F.Paste")
			(net "GND")
		)
		(pad "2" smd rect
			(at 0.7 0 180)
			(size 1.1 1.05)
			(layers "F.Cu" "F.Mask" "F.Paste")
			(net "+3.3V")
		)
	)
	(footprint "Vault:RESC1608X55X30LL15T20"
		(layer "F.Cu")
		(at 133.738595 92.0786 180)
		(property "Reference" "R37"
			(at 2.2714 -0.026931 0)
			(unlocked yes)
			(layer "F.SilkS")
			(effects
				(font
					(size 0.762 0.762)
					(thickness 0.2286)
				)
			)
		)
		(property "Value" "10K"
			(at -2.657602 1.790085 90)
			(unlocked yes)
			(layer "F.SilkS")
			(hide yes)
			(effects
				(font
					(size 1.524 1.524)
					(thickness 0.254)
				)
			)
		)
		(sheetname "GPS_IMU_SENSORS")
		(sheetfile "GPS_IMU_SENSORS.kicad_sch")
		(duplicate_pad_numbers_are_jumpers no)
		(pad "1" smd rect
			(at -0.575 0 270)
			(size 0.85 0.75)
			(layers "F.Cu" "F.Mask" "F.Paste")
			(net "EXT_EEPROM_WP")
		)
		(pad "2" smd rect
			(at 0.575 0 270)
			(size 0.85 0.75)
			(layers "F.Cu" "F.Mask" "F.Paste")
			(net "+3.3V")
		)
	)
	(footprint "Vault:RESC1608X55X25NL10T15"
		(layer "F.Cu")
		(at 83.238595 110.0786 -90)
		(property "Reference" "R17"
			(at -2.9786 -0.026921 90)
			(unlocked yes)
			(layer "F.SilkS")
			(effects
				(font
					(size 0.762 0.762)
					(thickness 0.2286)
				)
			)
		)
		(property "Value" "49.9R"
			(at -2.911602 3.21199 180)
			(unlocked yes)
			(layer "F.SilkS")
			(hide yes)
			(effects
				(font
					(size 1.524 1.524)
					(thickness 0.254)
				)
			)
		)
		(sheetname "USER_IO")
		(sheetfile "USER_IO.kicad_sch")
		(duplicate_pad_numbers_are_jumpers no)
		(pad "1" smd rect
			(at -0.7 0)
			(size 0.9 0.7)
			(layers "F.Cu" "F.Mask" "F.Paste")
			(net "NetR17_1")
		)
		(pad "2" smd rect
			(at 0.7 0)
			(size 0.9 0.7)
			(layers "F.Cu" "F.Mask" "F.Paste")
			(net "NetAN2_1")
		)
	)
	(footprint "Vault:CAPC1608X87X45ML20T05"
		(layer "F.Cu")
		(at 111.988595 143.8786 -90)
		(property "Reference" "C2"
			(at -1.8 -0.593345 90)
			(unlocked yes)
			(layer "F.SilkS")
			(effects
				(font
					(size 0.762 0.762)
					(thickness 0.2286)
				)
				(justify left bottom)
			)
		)
		(property "Value" "0.1uF"
			(at 2.31879 1.4493 0)
			(unlocked yes)
			(layer "F.SilkS")
			(hide yes)
			(effects
				(font
					(size 1.524 1.524)
					(thickness 0.254)
				)
				(justify left bottom)
			)
		)
		(sheetname "POWER")
		(sheetfile "POWER.kicad_sch")
		(duplicate_pad_numbers_are_jumpers no)
		(pad "1" smd rect
			(at -0.7 0)
			(size 1.1 1.05)
			(layers "F.Cu" "F.Mask" "F.Paste")
			(net "GND")
		)
		(pad "2" smd rect
			(at 0.7 0)
			(size 1.1 1.05)
			(layers "F.Cu" "F.Mask" "F.Paste")
			(net "+12V")
		)
	)
	(footprint "Resistors:RESC1608X50N"
		(layer "F.Cu")
		(at 229.934595 106.8306 90)
		(property "Reference" "R2"
			(at 1.477 0.522345 90)
			(unlocked yes)
			(layer "F.SilkS")
			(effects
				(font
					(size 0.762 0.762)
					(thickness 0.2286)
				)
				(justify left bottom)
			)
		)
		(property "Value" "ERJ-3EKF4702V"
			(at -3.04419 -4.4323 0)
			(unlocked yes)
			(layer "F.SilkS")
			(hide yes)
			(effects
				(font
					(size 1.524 1.524)
					(thickness 0.254)
				)
				(justify left bottom)
			)
		)
		(sheetname "POWER")
		(sheetfile "POWER.kicad_sch")
		(duplicate_pad_numbers_are_jumpers no)
		(fp_line
			(start 0 -0.5)
			(end 0 0.5)
			(stroke
				(width 0.1524)
				(type solid)
			)
			(layer "F.SilkS")
		)
		(pad "1" smd rect
			(at -0.69 0 180)
			(size 1 0.72)
			(layers "F.Cu" "F.Mask" "F.Paste")
			(net "NetR2_1")
		)
		(pad "2" smd rect
			(at 0.69 0 180)
			(size 1 0.72)
			(layers "F.Cu" "F.Mask" "F.Paste")
			(net "+12V")
		)
	)
	(footprint "Resistors:RESC1608X50N"
		(layer "F.Cu")
		(at 236.288595 112.1786 90)
		(property "Reference" "R8"
			(at 1.5 0.393345 90)
			(unlocked yes)
			(layer "F.SilkS")
			(effects
				(font
					(size 0.762 0.762)
					(thickness 0.2286)
				)
				(justify left bottom)
			)
		)
		(property "Value" "ERJ-3EKF2201V"
			(at -3.04419 -4.4323 0)
			(unlocked yes)
			(layer "F.SilkS")
			(hide yes)
			(effects
				(font
					(size 1.524 1.524)
					(thickness 0.254)
				)
				(justify left bottom)
			)
		)
		(sheetname "POWER")
		(sheetfile "POWER.kicad_sch")
		(duplicate_pad_numbers_are_jumpers no)
		(fp_line
			(start 0 -0.5)
			(end 0 0.5)
			(stroke
				(width 0.1524)
				(type solid)
			)
			(layer "F.SilkS")
		)
		(pad "1" smd rect
			(at -0.69 0 180)
			(size 1 0.72)
			(layers "F.Cu" "F.Mask" "F.Paste")
			(net "GND")
		)
		(pad "2" smd rect
			(at 0.69 0 180)
			(size 1 0.72)
			(layers "F.Cu" "F.Mask" "F.Paste")
			(net "NetC20_1")
		)
	)
	(footprint "Resistors:RESC1608X50N"
		(layer "F.Cu")
		(at 232.982595 114.4506)
		(property "Reference" "R4"
			(at -0.619 1.771345 0)
			(unlocked yes)
			(layer "F.SilkS")
			(effects
				(font
					(size 0.762 0.762)
					(thickness 0.2286)
				)
				(justify left bottom)
			)
		)
		(property "Value" "ERJ-3EKF4702V"
			(at -4.4323 3.04419 0)
			(unlocked yes)
			(layer "F.SilkS")
			(hide yes)
			(effects
				(font
					(size 1.524 1.524)
					(thickness 0.254)
				)
				(justify left bottom)
			)
		)
		(sheetname "POWER")
		(sheetfile "POWER.kicad_sch")
		(duplicate_pad_numbers_are_jumpers no)
		(fp_line
			(start 0 0.5)
			(end 0 -0.5)
			(stroke
				(width 0.1524)
				(type solid)
			)
			(layer "F.SilkS")
		)
		(pad "1" smd rect
			(at -0.69 0 90)
			(size 1 0.72)
			(layers "F.Cu" "F.Mask" "F.Paste")
			(net "+5.0V")
		)
		(pad "2" smd rect
			(at 0.69 0 90)
			(size 1 0.72)
			(layers "F.Cu" "F.Mask" "F.Paste")
			(net "NetR4_2")
		)
	)
	(footprint "Passives:DIOM1608X06N"
		(layer "F.Cu")
		(at 79.989925 53.2366 90)
		(property "Reference" "D12"
			(at -1.45369 -1.231865 90)
			(unlocked yes)
			(layer "F.SilkS")
			(effects
				(font
					(size 0.762 0.762)
					(thickness 0.2286)
				)
				(justify left bottom)
			)
		)
		(property "Value" "RED"
			(at -4.13639 -0.5715 0)
			(unlocked yes)
			(layer "F.SilkS")
			(hide yes)
			(effects
				(font
					(size 1.524 1.524)
					(thickness 0.254)
				)
				(justify left bottom)
			)
		)
		(sheetname "USER_IO")
		(sheetfile "USER_IO.kicad_sch")
		(duplicate_pad_numbers_are_jumpers no)
		(fp_circle
			(center -1.275 -0.725)
			(end -1.225 -0.725)
			(stroke
				(width 0.1)
				(type solid)
			)
			(fill no)
			(layer "F.SilkS")
		)
		(pad "1" smd rect
			(at -0.725 0 180)
			(size 0.85 1)
			(layers "F.Cu" "F.Mask" "F.Paste")
			(net "NetD12_1")
		)
		(pad "2" smd rect
			(at 0.725 0 180)
			(size 0.85 1)
			(layers "F.Cu" "F.Mask" "F.Paste")
			(net "+3.3V")
		)
	)
	(footprint "Vault:CAPC1608X87X45ML20T05"
		(layer "F.Cu")
		(at 227.648595 119.6576)
		(property "Reference" "C15"
			(at 1.74 0.414345 0)
			(unlocked yes)
			(layer "F.SilkS")
			(effects
				(font
					(size 0.762 0.762)
					(thickness 0.2286)
				)
				(justify left bottom)
			)
		)
		(property "Value" "0.1uF"
			(at -1.1811 5.63499 0)
			(unlocked yes)
			(layer "F.SilkS")
			(hide yes)
			(effects
				(font
					(size 1.524 1.524)
					(thickness 0.254)
				)
				(justify left bottom)
			)
		)
		(sheetname "POWER")
		(sheetfile "POWER.kicad_sch")
		(duplicate_pad_numbers_are_jumpers no)
		(pad "1" smd rect
			(at -0.7 0 90)
			(size 1.1 1.05)
			(layers "F.Cu" "F.Mask" "F.Paste")
			(net "GND")
		)
		(pad "2" smd rect
			(at 0.7 0 90)
			(size 1.1 1.05)
			(layers "F.Cu" "F.Mask" "F.Paste")
			(net "+5.0V")
		)
	)
	(footprint "Vault:RESC1608X55X25LL10T15"
		(layer "F.Cu")
		(at 190.738595 88.0786)
		(property "Reference" "R10"
			(at -2.2714 -0.223069 0)
			(unlocked yes)
			(layer "F.SilkS")
			(effects
				(font
					(size 0.762 0.762)
					(thickness 0.2286)
				)
			)
		)
		(property "Value" "4.7K"
			(at -2.657602 2.60264 270)
			(unlocked yes)
			(layer "F.SilkS")
			(hide yes)
			(effects
				(font
					(size 1.524 1.524)
					(thickness 0.254)
				)
			)
		)
		(sheetname "MAC")
		(sheetfile "MAC.kicad_sch")
		(duplicate_pad_numbers_are_jumpers no)
		(pad "1" smd rect
			(at -0.65 0 90)
			(size 0.8 0.6)
			(layers "F.Cu" "F.Mask" "F.Paste")
			(net "GND")
		)
		(pad "2" smd rect
			(at 0.65 0 90)
			(size 0.8 0.6)
			(layers "F.Cu" "F.Mask" "F.Paste")
			(net "FPGA_MAC_PPS_IN1-")
		)
	)
	(footprint "Passives:IND_PM124SH"
		(layer "F.Cu")
		(at 219.012595 118.6416 90)
		(property "Reference" "L1"
			(at 5.456745 -8.78815 0)
			(unlocked yes)
			(layer "F.SilkS")
			(effects
				(font
					(size 0.762 0.762)
					(thickness 0.2286)
				)
				(justify left bottom)
			)
		)
		(property "Value" "PM124SH-100M-RC"
			(at -10.00379 -10.8331 0)
			(unlocked yes)
			(layer "F.SilkS")
			(hide yes)
			(effects
				(font
					(size 1.524 1.524)
					(thickness 0.254)
				)
				(justify left bottom)
			)
		)
		(sheetname "POWER")
		(sheetfile "POWER.kicad_sch")
		(duplicate_pad_numbers_are_jumpers no)
		(fp_line
			(start 6.681 -6.4)
			(end 6.681 6.4)
			(stroke
				(width 0.254)
				(type solid)
			)
			(layer "F.SilkS")
		)
		(fp_line
			(start -6.681 -6.4)
			(end 6.681 -6.4)
			(stroke
				(width 0.254)
				(type solid)
			)
			(layer "F.SilkS")
		)
		(fp_line
			(start -6.681 -6.4)
			(end -6.681 6.4)
			(stroke
				(width 0.254)
				(type solid)
			)
			(layer "F.SilkS")
		)
		(fp_line
			(start -6.681 6.4)
			(end 6.681 6.4)
			(stroke
				(width 0.254)
				(type solid)
			)
			(layer "F.SilkS")
		)
		(pad "1" smd rect
			(at -4.85 0 90)
			(size 2.9 5.4)
			(layers "F.Cu" "F.Mask" "F.Paste")
			(net "+5.0V")
		)
		(pad "2" smd rect
			(at 4.85 0 90)
			(size 2.9 5.4)
			(layers "F.Cu" "F.Mask" "F.Paste")
			(net "NetC4_2")
		)
	)
	(footprint "Vault:TECO-1909763-1_V"
		(layer "F.Cu")
		(at 71.838595 97.5786 90)
		(property "Reference" "J6"
			(at -1.271395 2.926921 90)
			(unlocked yes)
			(layer "F.SilkS")
			(effects
				(font
					(size 0.762 0.762)
					(thickness 0.2286)
				)
			)
		)
		(property "Value" "1909763-1"
			(at 4.608085 3.749802 90)
			(unlocked yes)
			(layer "F.SilkS")
			(hide yes)
			(effects
				(font
					(size 1.524 1.524)
					(thickness 0.254)
				)
			)
		)
		(sheetname "USER_IO")
		(sheetfile "USER_IO.kicad_sch")
		(duplicate_pad_numbers_are_jumpers no)
		(fp_line
			(start -0.55 -1.3)
			(end 0.55 -1.3)
			(stroke
				(width 0.2)
				(type solid)
			)
			(layer "F.SilkS")
		)
		(fp_circle
			(center -1.778 1.65)
			(end -1.653 1.65)
			(stroke
				(width 0.25)
				(type solid)
			)
			(fill no)
			(layer "F.SilkS")
		)
		(pad "1" smd rect
			(at -1.475 0 90)
			(size 1.05 2.2)
			(layers "F.Cu" "F.Mask" "F.Paste")
			(net "GND")
		)
		(pad "2" smd rect
			(at 0 1.525 90)
			(size 1 1.05)
			(layers "F.Cu" "F.Mask" "F.Paste")
			(net "NetAN1_1")
		)
		(pad "3" smd rect
			(at 1.475 0 90)
			(size 1.05 2.2)
			(layers "F.Cu" "F.Mask" "F.Paste")
			(net "GND")
		)
	)
	(footprint "Passives:SOT65P210X110-3N"
		(layer "F.Cu")
		(at 102.488595 69.0786 180)
		(property "Reference" "D6"
			(at 1.5 -2.593345 0)
			(unlocked yes)
			(layer "F.SilkS")
			(effects
				(font
					(size 0.762 0.762)
					(thickness 0.2286)
				)
				(justify left bottom)
			)
		)
		(property "Value" "BAT54SW"
			(at 1.5875 -3.88239 0)
			(unlocked yes)
			(layer "F.SilkS")
			(hide yes)
			(effects
				(font
					(size 1.524 1.524)
					(thickness 0.254)
				)
				(justify left bottom)
			)
		)
		(sheetname "PCIe_JTAG")
		(sheetfile "PCIe_JTAG.kicad_sch")
		(duplicate_pad_numbers_are_jumpers no)
		(fp_line
			(start 0.675 1.1)
			(end -0.325 1.1)
			(stroke
				(width 0.2)
				(type solid)
			)
			(layer "F.SilkS")
		)
		(fp_line
			(start 0.675 0.65)
			(end 0.675 1.1)
			(stroke
				(width 0.2)
				(type solid)
			)
			(layer "F.SilkS")
		)
		(fp_line
			(start 0.675 -1.1)
			(end 0.675 -0.65)
			(stroke
				(width 0.2)
				(type solid)
			)
			(layer "F.SilkS")
		)
		(fp_line
			(start 0.675 -1.1)
			(end -0.325 -1.1)
			(stroke
				(width 0.2)
				(type solid)
			)
			(layer "F.SilkS")
		)
		(fp_circle
			(center -1.125 -1.45)
			(end -1.125 -1.325)
			(stroke
				(width 0.25)
				(type solid)
			)
			(fill no)
			(layer "F.SilkS")
		)
		(pad "1" smd rect
			(at -1.125 -0.65 270)
			(size 0.5 0.9)
			(layers "F.Cu" "F.Mask" "F.Paste")
			(net "GND")
		)
		(pad "2" smd rect
			(at -1.125 0.65 270)
			(size 0.5 0.9)
			(layers "F.Cu" "F.Mask" "F.Paste")
			(net "+3.3V")
		)
		(pad "3" smd rect
			(at 1.125 0 270)
			(size 0.5 0.9)
			(layers "F.Cu" "F.Mask" "F.Paste")
			(net "FPGA_TDO")
		)
	)
)
